# T6G (Grand Teton) — schematic netlist excerpt (pin names and nets, part order shuffled) for the footprints in the layout excerpt that follows; sources: Cadence DE-HDL packaged netlist, KiCad conversion of 04192023_DAF0TMB3IC0_F0TG_MB_C_brd_V02_OCP.brd

C2135  Q_CAP  22UF 4V 20% X6S  pkg C0402  page 68 : A = PVDDCR_SOC_P0 ; B = GND
PC592_2  Q_CAP  22UF 16V 20% X6S  pkg C0805  page 198 : A = SW_P12V_AUX_PVDDCR_SOC_P0_FLT ; B = GND
C120  Q_CAP  0.1UF 25V 10% X7R  pkg 0402  page 94 : A = P3V3_AUX ; B = GND

(kicad_pcb
	(version 20260206)
	(generator "pcbnew")
	(generator_version "10.0")
	(general
		(thickness 1.6)
		(legacy_teardrops no)
	)
	(paper "A4")
	(title_block
		(title "04192023_DAF0TMB3IC0_F0TG_MB_C_brd_V02_OCP.brd")
		(comment 1 "Grand Teton / footprints 6572-6574 of 8354")
	)
	(layers
		(0 "F.Cu" signal "TOP")
		(4 "In1.Cu" signal "GND")
		(6 "In2.Cu" signal "IN1")
		(8 "In3.Cu" signal "GND1")
		(10 "In4.Cu" signal "IN2")
		(12 "In5.Cu" signal "GND2")
		(14 "In6.Cu" signal "IN3")
		(16 "In7.Cu" signal "GND3")
		(18 "In8.Cu" signal "VCC")
		(20 "In9.Cu" signal "VCC1")
		(22 "In10.Cu" signal "GND4")
		(24 "In11.Cu" signal "IN4")
		(26 "In12.Cu" signal "GND5")
		(28 "In13.Cu" signal "IN5")
		(30 "In14.Cu" signal "GND6")
		(32 "In15.Cu" signal "IN6")
		(34 "In16.Cu" signal "GND7")
		(2 "B.Cu" signal "BOTTOM")
		(9 "F.Adhes" user "F.Adhesive")
		(11 "B.Adhes" user "B.Adhesive")
		(13 "F.Paste" user "Package Geometry/Pastemask Top")
		(15 "B.Paste" user "Package Geometry/Pastemask Bottom")
		(5 "F.SilkS" user "Ref Des/Silkscreen Top")
		(7 "B.SilkS" user "Ref Des/Silkscreen Bottom")
		(1 "F.Mask" user "Board Geometry/Soldermask Top")
		(3 "B.Mask" user "Board Geometry/Soldermask Bottom")
		(17 "Dwgs.User" user "User.Drawings")
		(19 "Cmts.User" user "User.Comments")
		(21 "Eco1.User" user "User.Eco1")
		(23 "Eco2.User" user "User.Eco2")
		(25 "Edge.Cuts" user "Board Geometry/Outline")
		(27 "Margin" user)
		(31 "F.CrtYd" user "Package Geometry/Place Bound Top")
		(29 "B.CrtYd" user "Package Geometry/Place Bound Bottom")
		(35 "F.Fab" user "Ref Des/Assembly Top")
		(33 "B.Fab" user "Ref Des/Assembly Bottom")
	)
	(footprint ""
		(layer "B.Cu")
		(at 423.256456 -193.99631)
		(property "Reference" "C120"
			(at 0 0 0)
			(layer "B.SilkS")
			(hide yes)
			(effects
				(font
					(size 1.27 1.27)
				)
				(justify mirror)
			)
		)
		(property "Value" ""
			(at 0 0 0)
			(layer "B.Fab")
			(effects
				(font
					(size 1.27 1.27)
				)
				(justify mirror)
			)
		)
		(duplicate_pad_numbers_are_jumpers no)
		(fp_line
			(start -0.7874 -0.4064)
			(end -0.7874 0.4064)
			(stroke
				(width 0.1524)
				(type default)
			)
			(layer "B.SilkS")
		)
		(fp_line
			(start -0.7874 0.4064)
			(end 0.7874 0.4064)
			(stroke
				(width 0.1524)
				(type default)
			)
			(layer "B.SilkS")
		)
		(fp_line
			(start 0.7874 -0.4064)
			(end -0.7874 -0.4064)
			(stroke
				(width 0.1524)
				(type default)
			)
			(layer "B.SilkS")
		)
		(fp_line
			(start 0.7874 0.4064)
			(end 0.7874 -0.4064)
			(stroke
				(width 0.1524)
				(type default)
			)
			(layer "B.SilkS")
		)
		(fp_line
			(start -0.67945 -0.3048)
			(end -0.67945 0.3048)
			(stroke
				(width 0.1)
				(type default)
			)
			(layer "B.Fab")
		)
		(fp_line
			(start -0.67945 0.3048)
			(end -0.120396 0.3048)
			(stroke
				(width 0.1)
				(type default)
			)
			(layer "B.Fab")
		)
		(fp_line
			(start -0.12065 -0.3048)
			(end -0.67945 -0.3048)
			(stroke
				(width 0.1)
				(type default)
			)
			(layer "B.Fab")
		)
		(fp_line
			(start -0.12065 -0.2794)
			(end -0.12065 -0.3048)
			(stroke
				(width 0.1)
				(type default)
			)
			(layer "B.Fab")
		)
		(fp_line
			(start -0.120396 0.2794)
			(end 0.12065 0.2794)
			(stroke
				(width 0.1)
				(type default)
			)
			(layer "B.Fab")
		)
		(fp_line
			(start -0.120396 0.3048)
			(end -0.120396 0.2794)
			(stroke
				(width 0.1)
				(type default)
			)
			(layer "B.Fab")
		)
		(fp_line
			(start 0.12065 -0.305054)
			(end 0.12065 -0.2794)
			(stroke
				(width 0.1)
				(type default)
			)
			(layer "B.Fab")
		)
		(fp_line
			(start 0.12065 -0.2794)
			(end -0.12065 -0.2794)
			(stroke
				(width 0.1)
				(type default)
			)
			(layer "B.Fab")
		)
		(fp_line
			(start 0.12065 0.2794)
			(end 0.12065 0.3048)
			(stroke
				(width 0.1)
				(type default)
			)
			(layer "B.Fab")
		)
		(fp_line
			(start 0.12065 0.3048)
			(end 0.67945 0.3048)
			(stroke
				(width 0.1)
				(type default)
			)
			(layer "B.Fab")
		)
		(fp_line
			(start 0.67945 -0.305054)
			(end 0.12065 -0.305054)
			(stroke
				(width 0.1)
				(type default)
			)
			(layer "B.Fab")
		)
		(fp_line
			(start 0.67945 0.3048)
			(end 0.67945 -0.305054)
			(stroke
				(width 0.1)
				(type default)
			)
			(layer "B.Fab")
		)
		(pad "1" smd circle
			(at 0.40005 0 180)
			(size 0 0)
			(layers "B.Cu" "B.Mask" "B.Paste")
			(net "P3V3_AUX")
		)
		(pad "2" smd circle
			(at -0.40005 0 180)
			(size 0 0)
			(layers "B.Cu" "B.Mask" "B.Paste")
			(net "GND")
		)
	)
	(footprint ""
		(layer "B.Cu")
		(at 403.088856 -168.717468 -90)
		(property "Reference" "PC592_2"
			(at 0 0 90)
			(layer "B.SilkS")
			(hide yes)
			(effects
				(font
					(size 1.27 1.27)
				)
				(justify mirror)
			)
		)
		(property "Value" ""
			(at 0 0 90)
			(layer "B.Fab")
			(effects
				(font
					(size 1.27 1.27)
				)
				(justify mirror)
			)
		)
		(duplicate_pad_numbers_are_jumpers no)
		(fp_line
			(start -1.524 0.762)
			(end 1.524 0.762)
			(stroke
				(width 0.1524)
				(type default)
			)
			(layer "B.SilkS")
		)
		(fp_line
			(start 1.524 0.762)
			(end 1.524 -0.762)
			(stroke
				(width 0.1524)
				(type default)
			)
			(layer "B.SilkS")
		)
		(fp_line
			(start -1.524 -0.762)
			(end -1.524 0.762)
			(stroke
				(width 0.1524)
				(type default)
			)
			(layer "B.SilkS")
		)
		(fp_line
			(start 1.524 -0.762)
			(end -1.524 -0.762)
			(stroke
				(width 0.1524)
				(type default)
			)
			(layer "B.SilkS")
		)
		(fp_line
			(start -1.1049 0.724916)
			(end -1.1049 -0.724916)
			(stroke
				(width 0.1)
				(type default)
			)
			(layer "B.Fab")
		)
		(fp_line
			(start 1.1049 0.724916)
			(end -1.1049 0.724916)
			(stroke
				(width 0.1)
				(type default)
			)
			(layer "B.Fab")
		)
		(fp_line
			(start -1.1049 -0.724916)
			(end 1.1049 -0.724916)
			(stroke
				(width 0.1)
				(type default)
			)
			(layer "B.Fab")
		)
		(fp_line
			(start 1.1049 -0.724916)
			(end 1.1049 0.724916)
			(stroke
				(width 0.1)
				(type default)
			)
			(layer "B.Fab")
		)
		(pad "1" smd rect
			(at 0.889 0 270)
			(size 1.016 1.27)
			(layers "B.Cu" "B.Mask" "B.Paste")
			(net "SW_P12V_AUX_PVDDCR_SOC_P0_FLT")
		)
		(pad "2" smd rect
			(at -0.889 0 270)
			(size 1.016 1.27)
			(layers "B.Cu" "B.Mask" "B.Paste")
			(net "GND")
		)
	)
	(footprint ""
		(layer "B.Cu")
		(at 360.366056 -256.012188 -90)
		(property "Reference" "C2135"
			(at 0 0 90)
			(layer "B.SilkS")
			(hide yes)
			(effects
				(font
					(size 1.27 1.27)
				)
				(justify mirror)
			)
		)
		(property "Value" ""
			(at 0 0 90)
			(layer "B.Fab")
			(effects
				(font
					(size 1.27 1.27)
				)
				(justify mirror)
			)
		)
		(duplicate_pad_numbers_are_jumpers no)
		(fp_line
			(start -0.7874 0.4064)
			(end 0.7874 0.4064)
			(stroke
				(width 0.1524)
				(type default)
			)
			(layer "B.SilkS")
		)
		(fp_line
			(start 0.7874 0.4064)
			(end 0.7874 -0.4064)
			(stroke
				(width 0.1524)
				(type default)
			)
			(layer "B.SilkS")
		)
		(fp_line
			(start -0.7874 -0.4064)
			(end -0.7874 0.4064)
			(stroke
				(width 0.1524)
				(type default)
			)
			(layer "B.SilkS")
		)
		(fp_line
			(start 0.7874 -0.4064)
			(end -0.7874 -0.4064)
			(stroke
				(width 0.1524)
				(type default)
			)
			(layer "B.SilkS")
		)
		(fp_line
			(start -0.67945 0.3048)
			(end -0.120396 0.3048)
			(stroke
				(width 0.1)
				(type default)
			)
			(layer "B.Fab")
		)
		(fp_line
			(start -0.120396 0.3048)
			(end -0.120396 0.2794)
			(stroke
				(width 0.1)
				(type default)
			)
			(layer "B.Fab")
		)
		(fp_line
			(start 0.12065 0.3048)
			(end 0.67945 0.3048)
			(stroke
				(width 0.1)
				(type default)
			)
			(layer "B.Fab")
		)
		(fp_line
			(start 0.67945 0.3048)
			(end 0.67945 -0.305054)
			(stroke
				(width 0.1)
				(type default)
			)
			(layer "B.Fab")
		)
		(fp_line
			(start -0.120396 0.2794)
			(end 0.12065 0.2794)
			(stroke
				(width 0.1)
				(type default)
			)
			(layer "B.Fab")
		)
		(fp_line
			(start 0.12065 0.2794)
			(end 0.12065 0.3048)
			(stroke
				(width 0.1)
				(type default)
			)
			(layer "B.Fab")
		)
		(fp_line
			(start -0.12065 -0.2794)
			(end -0.12065 -0.3048)
			(stroke
				(width 0.1)
				(type default)
			)
			(layer "B.Fab")
		)
		(fp_line
			(start 0.12065 -0.2794)
			(end -0.12065 -0.2794)
			(stroke
				(width 0.1)
				(type default)
			)
			(layer "B.Fab")
		)
		(fp_line
			(start -0.67945 -0.3048)
			(end -0.67945 0.3048)
			(stroke
				(width 0.1)
				(type default)
			)
			(layer "B.Fab")
		)
		(fp_line
			(start -0.12065 -0.3048)
			(end -0.67945 -0.3048)
			(stroke
				(width 0.1)
				(type default)
			)
			(layer "B.Fab")
		)
		(fp_line
			(start 0.12065 -0.305054)
			(end 0.12065 -0.2794)
			(stroke
				(width 0.1)
				(type default)
			)
			(layer "B.Fab")
		)
		(fp_line
			(start 0.67945 -0.305054)
			(end 0.12065 -0.305054)
			(stroke
				(width 0.1)
				(type default)
			)
			(layer "B.Fab")
		)
		(pad "1" smd circle
			(at 0.40005 0 90)
			(size 0 0)
			(layers "B.Cu" "B.Mask" "B.Paste")
			(net "PVDDCR_SOC_P0")
		)
		(pad "2" smd circle
			(at -0.40005 0 90)
			(size 0 0)
			(layers "B.Cu" "B.Mask" "B.Paste")
			(net "GND")
		)
	)
)
